G04*
G04 #@! TF.GenerationSoftware,Altium Limited,Altium Designer,23.0.1 (38)*
G04*
G04 Layer_Color=32768*
%FSLAX25Y25*%
%MOIN*%
G70*
G04*
G04 #@! TF.SameCoordinates,C48E81DB-6E20-4E2D-80E6-7C5AFAA1A21F*
G04*
G04*
G04 #@! TF.FilePolarity,Positive*
G04*
G01*
G75*
%ADD16C,0.00394*%
D16*
X148579Y-372099D02*
G03*
X134209Y-372099I-7185J0D01*
G01*
M02*
